(kicad_pcb
	(version 20221018)
	(generator pcbnew)
	(general
    (thickness 1.62)
  )
	(paper "A4")
	(title_block
    (title "ECP5 - Datacenter Secure Control Module (DC-SCM)")
    (date "2024-07-01")
    (rev "1.2.1")
		(comment 9 "footprint 183 of 506 (J5), pads 1-117 of 168")
	)
	(layers
    (0 "F.Cu" signal)
    (1 "In1.Cu" power)
    (2 "In2.Cu" signal)
    (3 "In3.Cu" power)
    (4 "In4.Cu" power)
    (5 "In5.Cu" signal)
    (6 "In6.Cu" power)
    (31 "B.Cu" signal)
    (32 "B.Adhes" user "B.Adhesive")
    (33 "F.Adhes" user "F.Adhesive")
    (34 "B.Paste" user)
    (35 "F.Paste" user)
    (36 "B.SilkS" user "B.Silkscreen")
    (37 "F.SilkS" user "F.Silkscreen")
    (38 "B.Mask" user)
    (39 "F.Mask" user)
    (40 "Dwgs.User" user "User.Drawings")
    (41 "Cmts.User" user "User.Comments")
    (42 "Eco1.User" user "User.Eco1")
    (43 "Eco2.User" user "User.Eco2")
    (44 "Edge.Cuts" user)
    (45 "Margin" user)
    (46 "B.CrtYd" user "B.Courtyard")
    (47 "F.CrtYd" user "F.Courtyard")
    (48 "B.Fab" user)
    (49 "F.Fab" user)
  )
	(footprint "antmicro-footprints:SFF-TA-1002-4C+"
    (layer "F.Cu")
    (at 104.89 177.345)
    (property "Author" "Antmicro")
    (property "DNP" "DNP")
    (property "License" "Apache-2.0")
    (property "MPN" "SFF-TA-1002-4C+")
    (property "Manufacturer" "Amphenol")
    (property "Sheetfile" "edge-connector.kicad_sch")
    (property "Sheetname" "Edge connector")
    (property "ki_description" "PCI connector")
    (property "ki_keywords" "CONNECTOR")
    (attr exclude_from_pos_files)
    (fp_text reference "J5" (at -0.83 -8.9) (layer "F.SilkS")
        (effects (font (size 0.7 0.7) (thickness 0.127)))
    )
    (fp_text value "SFF-TA-1002-4C+" (at -24.2 4.8) (layer "F.Fab")
        (effects (font (size 1 1) (thickness 0.15)))
    )
    (pad "A1" smd rect (at -18.205 -0.2) (size 0.38 1.72) (layers "B.Cu" "B.Mask")
      (net 37 "I2C[0]_SCL") (pinfunction "A1") (pintype "passive"))
    (pad "A2" smd rect (at -17.6 -0.2) (size 0.38 1.72) (layers "B.Cu" "B.Mask")
      (net 38 "I2C[0]_SDA") (pinfunction "A2") (pintype "passive"))
    (pad "A3" smd rect (at -17 -0.2) (size 0.38 1.72) (layers "B.Cu" "B.Mask")
      (net 28 "I2C[1]_SCL") (pinfunction "A3") (pintype "passive"))
    (pad "A4" smd rect (at -16.4 -0.2) (size 0.38 1.72) (layers "B.Cu" "B.Mask")
      (net 29 "I2C[1]_SDA") (pinfunction "A4") (pintype "passive"))
    (pad "A5" smd rect (at -15.8 -0.2) (size 0.38 1.72) (layers "B.Cu" "B.Mask")
      (net 32 "I2C[2]_SCL") (pinfunction "A5") (pintype "passive"))
    (pad "A6" smd rect (at -15.2 -0.2) (size 0.38 1.72) (layers "B.Cu" "B.Mask")
      (net 31 "I2C[2]_SDA") (pinfunction "A6") (pintype "passive"))
    (pad "A7" smd rect (at -14.6 -0.2) (size 0.38 1.72) (layers "B.Cu" "B.Mask")
      (net 25 "I2C[3]_SCL") (pinfunction "A7") (pintype "passive"))
    (pad "A8" smd rect (at -14 -0.2) (size 0.38 1.72) (layers "B.Cu" "B.Mask")
      (net 27 "I2C[3]_SDA") (pinfunction "A8") (pintype "passive"))
    (pad "A9" smd rect (at -13.4 -0.2) (size 0.38 1.72) (layers "B.Cu" "B.Mask")
      (net 36 "I2C[4]_SCL") (pinfunction "A9") (pintype "passive"))
    (pad "A10" smd rect (at -12.8 -0.2) (size 0.38 1.72) (layers "B.Cu" "B.Mask")
      (net 33 "I2C[4]_SDA") (pinfunction "A10") (pintype "passive"))
    (pad "A11" smd rect (at -12.2 0) (size 0.38 2.12) (layers "B.Cu" "B.Mask")
      (net 24 "I2C[5]_SCL") (pinfunction "A11") (pintype "passive"))
    (pad "A12" smd rect (at -11.6 -0.2) (size 0.38 1.72) (layers "B.Cu" "B.Mask")
      (net 23 "I2C[5]_SDA") (pinfunction "A12") (pintype "passive"))
    (pad "A13" smd rect (at -11 -0.2) (size 0.38 1.72) (layers "B.Cu" "B.Mask")
      (net 1 "GND") (pinfunction "A13") (pintype "passive"))
    (pad "A14" smd rect (at -10.4 0) (size 0.38 2.12) (layers "B.Cu" "B.Mask")
      (net 103 "CLK_100M_PCIE_DP") (pinfunction "A14") (pintype "passive"))
    (pad "A15" smd rect (at -9.8 -0.2) (size 0.38 1.72) (layers "B.Cu" "B.Mask")
      (net 104 "CLK_100M_PCIE_DN") (pinfunction "A15") (pintype "passive"))
    (pad "A16" smd rect (at -9.2 -0.2) (size 0.38 1.72) (layers "B.Cu" "B.Mask")
      (net 1 "GND") (pinfunction "A16") (pintype "passive"))
    (pad "A17" smd rect (at -8.6 0) (size 0.38 2.12) (layers "B.Cu" "B.Mask")
      (net 105 "PCIE_BMC_TX_DP") (pinfunction "A17") (pintype "passive"))
    (pad "A18" smd rect (at -8 -0.2) (size 0.38 1.72) (layers "B.Cu" "B.Mask")
      (net 106 "PCIE_BMC_TX_DN") (pinfunction "A18") (pintype "passive"))
    (pad "A19" smd rect (at -7.4 -0.2) (size 0.38 1.72) (layers "B.Cu" "B.Mask")
      (net 1 "GND") (pinfunction "A19") (pintype "passive"))
    (pad "A20" smd rect (at -6.8 0) (size 0.38 2.12) (layers "B.Cu" "B.Mask")
      (net 107 "PCIE_BMC_RX_DP") (pinfunction "A20") (pintype "passive"))
    (pad "A21" smd rect (at -6.2 -0.2) (size 0.38 1.72) (layers "B.Cu" "B.Mask")
      (net 108 "PCIE_BMC_RX_DN") (pinfunction "A21") (pintype "passive"))
    (pad "A22" smd rect (at -5.6 -0.2) (size 0.38 1.72) (layers "B.Cu" "B.Mask")
      (net 1 "GND") (pinfunction "A22") (pintype "passive"))
    (pad "A23" smd rect (at -5 -0.2) (size 0.38 1.72) (layers "B.Cu" "B.Mask")
      (net 34 "I2C[6]_SCL") (pinfunction "A23") (pintype "passive"))
    (pad "A24" smd rect (at -4.4 -0.2) (size 0.38 1.72) (layers "B.Cu" "B.Mask")
      (net 35 "I2C[6]_SDA") (pinfunction "A24") (pintype "passive"))
    (pad "A25" smd rect (at -3.8 -0.2) (size 0.38 1.72) (layers "B.Cu" "B.Mask")
      (net 26 "I2C[7]_SCL") (pinfunction "A25") (pintype "passive"))
    (pad "A26" smd rect (at -3.2 -0.2) (size 0.38 1.72) (layers "B.Cu" "B.Mask")
      (net 30 "I2C[7]_SDA") (pinfunction "A26") (pintype "passive"))
    (pad "A27" smd rect (at -2.6 -0.2) (size 0.38 1.72) (layers "B.Cu" "B.Mask")
      (net 51 "I2C[8]_SCL") (pinfunction "A27") (pintype "passive"))
    (pad "A28" smd rect (at -2 -0.2) (size 0.38 1.72) (layers "B.Cu" "B.Mask")
      (net 52 "I2C[8]_SDA") (pinfunction "A28") (pintype "passive"))
    (pad "A29" smd rect (at 2.01 -0.2) (size 0.38 1.72) (layers "B.Cu" "B.Mask")
      (net 43 "I2C[9]_SCL") (pinfunction "A29") (pintype "passive"))
    (pad "A30" smd rect (at 2.6 -0.2) (size 0.38 1.72) (layers "B.Cu" "B.Mask")
      (net 44 "I2C[9]_SDA") (pinfunction "A30") (pintype "passive"))
    (pad "A31" smd rect (at 3.2 -0.2) (size 0.38 1.72) (layers "B.Cu" "B.Mask")
      (net 48 "I2C[10]_SCL") (pinfunction "A31") (pintype "passive"))
    (pad "A32" smd rect (at 3.8 -0.2) (size 0.38 1.72) (layers "B.Cu" "B.Mask")
      (net 47 "I2C[10]_SDA") (pinfunction "A32") (pintype "passive"))
    (pad "A33" smd rect (at 4.4 0) (size 0.38 2.12) (layers "B.Cu" "B.Mask")
      (net 1 "GND") (pinfunction "A33") (pintype "passive"))
    (pad "A34" smd rect (at 5 -0.2) (size 0.38 1.72) (layers "B.Cu" "B.Mask")
      (net 21 "JTAG_TCK") (pinfunction "A34") (pintype "passive"))
    (pad "A35" smd rect (at 5.6 -0.2) (size 0.38 1.72) (layers "B.Cu" "B.Mask")
      (net 22 "JTAG_TMS") (pinfunction "A35") (pintype "passive"))
    (pad "A36" smd rect (at 6.2 -0.2) (size 0.38 1.72) (layers "B.Cu" "B.Mask")
      (net 19 "JTAG_TDI") (pinfunction "A36") (pintype "passive"))
    (pad "A37" smd rect (at 6.8 -0.2) (size 0.38 1.72) (layers "B.Cu" "B.Mask")
      (net 20 "JTAG_TDO") (pinfunction "A37") (pintype "passive"))
    (pad "A38" smd rect (at 7.4 -0.2) (size 0.38 1.72) (layers "B.Cu" "B.Mask")
      (net 40 "I2C[11]_SCL") (pinfunction "A38") (pintype "passive"))
    (pad "A39" smd rect (at 8 -0.2) (size 0.38 1.72) (layers "B.Cu" "B.Mask")
      (net 42 "I2C[11]_SDA") (pinfunction "A39") (pintype "passive"))
    (pad "A40" smd rect (at 8.6 -0.2) (size 0.38 1.72) (layers "B.Cu" "B.Mask")
      (net 50 "I2C[12]_SCL") (pinfunction "A40") (pintype "passive"))
    (pad "A41" smd rect (at 9.2 -0.2) (size 0.38 1.72) (layers "B.Cu" "B.Mask")
      (net 49 "I2C[12]_SDA") (pinfunction "A41") (pintype "passive"))
    (pad "A42" smd rect (at 9.8 0) (size 0.38 2.12) (layers "B.Cu" "B.Mask")
      (net 1 "GND") (pinfunction "A42") (pintype "passive"))
    (pad "A43" smd rect (at 14.715 -0.2) (size 0.38 1.72) (layers "B.Cu" "B.Mask")
      (net 109 "HPM_FW_RECOVERY") (pinfunction "A43") (pintype "passive"))
    (pad "A44" smd rect (at 15.3 -0.2) (size 0.38 1.72) (layers "B.Cu" "B.Mask")
      (net 110 "HPM_STBY_RDY") (pinfunction "A44") (pintype "passive"))
    (pad "A45" smd rect (at 15.9 -0.2) (size 0.38 1.72) (layers "B.Cu" "B.Mask")
      (net 111 "HPM_STBY_EN") (pinfunction "A45") (pintype "passive"))
    (pad "A46" smd rect (at 16.5 -0.2) (size 0.38 1.72) (layers "B.Cu" "B.Mask")
      (net 112 "HPM_STBY_RST_N") (pinfunction "A46") (pintype "passive"))
    (pad "A47" smd rect (at 17.1 -0.2) (size 0.38 1.72) (layers "B.Cu" "B.Mask")
      (net 113 "SYS_PWRBTN_N") (pinfunction "A47") (pintype "passive"))
    (pad "A48" smd rect (at 17.7 -0.2) (size 0.38 1.72) (layers "B.Cu" "B.Mask")
      (net 114 "SYS_PWROK") (pinfunction "A48") (pintype "passive"))
    (pad "A49" smd rect (at 18.3 -0.2) (size 0.38 1.72) (layers "B.Cu" "B.Mask")
      (net 115 "DBP_PREQ_N") (pinfunction "A49") (pintype "passive"))
    (pad "A50" smd rect (at 18.9 -0.2) (size 0.38 1.72) (layers "B.Cu" "B.Mask")
      (net 116 "DBP_PRDY_N") (pinfunction "A50") (pintype "passive"))
    (pad "A51" smd rect (at 19.5 -0.2) (size 0.38 1.72) (layers "B.Cu" "B.Mask")
      (net 117 "RST_PLTRST_BUF_N") (pinfunction "A51") (pintype "passive"))
    (pad "A52" smd rect (at 20.1 -0.2) (size 0.38 1.72) (layers "B.Cu" "B.Mask")
      (net 118 "SPARE1") (pinfunction "A52") (pintype "passive"))
    (pad "A53" smd rect (at 20.7 -0.2) (size 0.38 1.72) (layers "B.Cu" "B.Mask")
      (net 119 "RoT_CPU_RST_N") (pinfunction "A53") (pintype "passive"))
    (pad "A54" smd rect (at 21.3 -0.2) (size 0.38 1.72) (layers "B.Cu" "B.Mask")
      (net 120 "CHASI#") (pinfunction "A54") (pintype "passive"))
    (pad "A55" smd rect (at 21.9 -0.2) (size 0.38 1.72) (layers "B.Cu" "B.Mask")
      (net 121 "SPARE0") (pinfunction "A55") (pintype "passive"))
    (pad "A56" smd rect (at 22.5 -0.2) (size 0.38 1.72) (layers "B.Cu" "B.Mask")
      (net 122 "IRQ_N") (pinfunction "A56") (pintype "passive"))
    (pad "A57" smd rect (at 23.1 -0.2) (size 0.38 1.72) (layers "B.Cu" "B.Mask")
      (net 123 "PRSNT1_N") (pinfunction "A57") (pintype "passive"))
    (pad "A58" smd rect (at 23.7 0) (size 0.38 2.12) (layers "B.Cu" "B.Mask")
      (net 1 "GND") (pinfunction "A58") (pintype "passive"))
    (pad "A59" smd rect (at 24.3 -0.2) (size 0.38 1.72) (layers "B.Cu" "B.Mask")
      (net 702 "PCIE_HPM_RX0_P") (pinfunction "A59") (pintype "passive"))
    (pad "A60" smd rect (at 24.9 -0.2) (size 0.38 1.72) (layers "B.Cu" "B.Mask")
      (net 703 "PCIE_HPM_RX0_N") (pinfunction "A60") (pintype "passive"))
    (pad "A61" smd rect (at 25.5 0) (size 0.38 2.12) (layers "B.Cu" "B.Mask")
      (net 1 "GND") (pinfunction "A61") (pintype "passive"))
    (pad "A62" smd rect (at 26.1 -0.2) (size 0.38 1.72) (layers "B.Cu" "B.Mask")
      (net 701 "PCIE_HPM_RX1_P") (pinfunction "A62") (pintype "passive"))
    (pad "A63" smd rect (at 26.7 -0.2) (size 0.38 1.72) (layers "B.Cu" "B.Mask")
      (net 700 "PCIE_HPM_RX1_N") (pinfunction "A63") (pintype "passive"))
    (pad "A64" smd rect (at 27.3 0) (size 0.38 2.12) (layers "B.Cu" "B.Mask")
      (net 1 "GND") (pinfunction "A64") (pintype "passive"))
    (pad "A65" smd rect (at 27.9 -0.2) (size 0.38 1.72) (layers "B.Cu" "B.Mask")
      (net 699 "PCIE_HPM_RX2_P") (pinfunction "A65") (pintype "passive"))
    (pad "A66" smd rect (at 28.5 -0.2) (size 0.38 1.72) (layers "B.Cu" "B.Mask")
      (net 698 "PCIE_HPM_RX2_N") (pinfunction "A66") (pintype "passive"))
    (pad "A67" smd rect (at 29.1 0) (size 0.38 2.12) (layers "B.Cu" "B.Mask")
      (net 1 "GND") (pinfunction "A67") (pintype "passive"))
    (pad "A68" smd rect (at 29.7 -0.2) (size 0.38 1.72) (layers "B.Cu" "B.Mask")
      (net 697 "PCIE_HPM_RX3_P") (pinfunction "A68") (pintype "passive"))
    (pad "A69" smd rect (at 30.3 -0.2) (size 0.38 1.72) (layers "B.Cu" "B.Mask")
      (net 696 "PCIE_HPM_RX3_N") (pinfunction "A69") (pintype "passive"))
    (pad "A70" smd rect (at 30.9 0) (size 0.38 2.12) (layers "B.Cu" "B.Mask")
      (net 1 "GND") (pinfunction "A70") (pintype "passive"))
    (pad "B1" smd rect (at -18.205 -0.2) (size 0.38 1.72) (layers "F.Cu" "F.Mask")
      (net 59 "ESPI_CLK") (pinfunction "B1") (pintype "passive"))
    (pad "B2" smd rect (at -17.6 -0.2) (size 0.38 1.72) (layers "F.Cu" "F.Mask")
      (net 60 "ESPI_CS0_N") (pinfunction "B2") (pintype "passive"))
    (pad "B3" smd rect (at -17 -0.2) (size 0.38 1.72) (layers "F.Cu" "F.Mask")
      (net 61 "ESPI_ALERT_N") (pinfunction "B3") (pintype "passive"))
    (pad "B4" smd rect (at -16.4 -0.2) (size 0.38 1.72) (layers "F.Cu" "F.Mask")
      (net 62 "ESPI_RESET_N") (pinfunction "B4") (pintype "passive"))
    (pad "B5" smd rect (at -15.8 -0.2) (size 0.38 1.72) (layers "F.Cu" "F.Mask")
      (net 63 "ESPI_IO0") (pinfunction "B5") (pintype "passive"))
    (pad "B6" smd rect (at -15.2 -0.2) (size 0.38 1.72) (layers "F.Cu" "F.Mask")
      (net 64 "ESPI_IO1") (pinfunction "B6") (pintype "passive"))
    (pad "B7" smd rect (at -14.6 -0.2) (size 0.38 1.72) (layers "F.Cu" "F.Mask")
      (net 65 "ESPI_IO2") (pinfunction "B7") (pintype "passive"))
    (pad "B8" smd rect (at -14 -0.2) (size 0.38 1.72) (layers "F.Cu" "F.Mask")
      (net 66 "ESPI_IO3") (pinfunction "B8") (pintype "passive"))
    (pad "B9" smd rect (at -13.4 -0.2) (size 0.38 1.72) (layers "F.Cu" "F.Mask")
      (net 67 "ESPI_CS1_N") (pinfunction "B9") (pintype "passive"))
    (pad "B10" smd rect (at -12.8 0) (size 0.38 2.12) (layers "F.Cu" "F.Mask")
      (net 1 "GND") (pinfunction "B10") (pintype "passive"))
    (pad "B11" smd rect (at -12.2 -0.2) (size 0.38 1.72) (layers "F.Cu" "F.Mask")
      (net 68 "QSPI0_CLK") (pinfunction "B11") (pintype "passive"))
    (pad "B12" smd rect (at -11.6 -0.2) (size 0.38 1.72) (layers "F.Cu" "F.Mask")
      (net 69 "QSPI0_CS0_N") (pinfunction "B12") (pintype "passive"))
    (pad "B13" smd rect (at -11 -0.2) (size 0.38 1.72) (layers "F.Cu" "F.Mask")
      (net 70 "QSPI0_D0") (pinfunction "B13") (pintype "passive"))
    (pad "B14" smd rect (at -10.4 -0.2) (size 0.38 1.72) (layers "F.Cu" "F.Mask")
      (net 71 "QSPI0_D1") (pinfunction "B14") (pintype "passive"))
    (pad "B15" smd rect (at -9.8 -0.2) (size 0.38 1.72) (layers "F.Cu" "F.Mask")
      (net 72 "QSPI0_D2") (pinfunction "B15") (pintype "passive"))
    (pad "B16" smd rect (at -9.2 -0.2) (size 0.38 1.72) (layers "F.Cu" "F.Mask")
      (net 73 "QSPI0_D3") (pinfunction "B16") (pintype "passive"))
    (pad "B17" smd rect (at -8.6 0) (size 0.38 2.12) (layers "F.Cu" "F.Mask")
      (net 1 "GND") (pinfunction "B17") (pintype "passive"))
    (pad "B18" smd rect (at -8 -0.2) (size 0.38 1.72) (layers "F.Cu" "F.Mask")
      (net 74 "NCSI_CLK") (pinfunction "B18") (pintype "passive"))
    (pad "B19" smd rect (at -7.4 -0.2) (size 0.38 1.72) (layers "F.Cu" "F.Mask")
      (net 75 "NCSI_CRS_DV") (pinfunction "B19") (pintype "passive"))
    (pad "B20" smd rect (at -6.8 -0.2) (size 0.38 1.72) (layers "F.Cu" "F.Mask")
      (net 76 "NCSI_TXEN") (pinfunction "B20") (pintype "passive"))
    (pad "B21" smd rect (at -6.2 -0.2) (size 0.38 1.72) (layers "F.Cu" "F.Mask")
      (net 77 "NCSI_TXD0") (pinfunction "B21") (pintype "passive"))
    (pad "B22" smd rect (at -5.6 -0.2) (size 0.38 1.72) (layers "F.Cu" "F.Mask")
      (net 78 "NCSI_TXD1") (pinfunction "B22") (pintype "passive"))
    (pad "B23" smd rect (at -5 -0.2) (size 0.38 1.72) (layers "F.Cu" "F.Mask")
      (net 79 "NCSI_RXER") (pinfunction "B23") (pintype "passive"))
    (pad "B24" smd rect (at -4.4 -0.2) (size 0.38 1.72) (layers "F.Cu" "F.Mask")
      (net 80 "NCSI_RXD0") (pinfunction "B24") (pintype "passive"))
    (pad "B25" smd rect (at -3.8 -0.2) (size 0.38 1.72) (layers "F.Cu" "F.Mask")
      (net 81 "NCSI_RXD1") (pinfunction "B25") (pintype "passive"))
    (pad "B26" smd rect (at -3.2 0) (size 0.38 2.12) (layers "F.Cu" "F.Mask")
      (net 1 "GND") (pinfunction "B26") (pintype "passive"))
    (pad "B27" smd rect (at -2.6 -0.2) (size 0.38 1.72) (layers "F.Cu" "F.Mask")
      (net 421 "unconnected-(J5-PadB27)") (pinfunction "B27") (pintype "passive+no_connect"))
    (pad "B28" smd rect (at -2 -0.2) (size 0.38 1.72) (layers "F.Cu" "F.Mask")
      (net 424 "unconnected-(J5-PadB28)") (pinfunction "B28") (pintype "passive+no_connect"))
    (pad "B29" smd rect (at 2.01 -0.2) (size 0.38 1.72) (layers "F.Cu" "F.Mask")
      (net 82 "SGPIO0_DO") (pinfunction "B29") (pintype "passive"))
    (pad "B30" smd rect (at 2.6 -0.2) (size 0.38 1.72) (layers "F.Cu" "F.Mask")
      (net 83 "SGPIO0_CLK") (pinfunction "B30") (pintype "passive"))
    (pad "B31" smd rect (at 3.2 -0.2) (size 0.38 1.72) (layers "F.Cu" "F.Mask")
      (net 84 "SGPIO0_DI") (pinfunction "B31") (pintype "passive"))
    (pad "B32" smd rect (at 3.8 -0.2) (size 0.38 1.72) (layers "F.Cu" "F.Mask")
      (net 85 "SGPIO0_LD") (pinfunction "B32") (pintype "passive"))
    (pad "B33" smd rect (at 4.4 0) (size 0.38 2.12) (layers "F.Cu" "F.Mask")
      (net 1 "GND") (pinfunction "B33") (pintype "passive"))
    (pad "B34" smd rect (at 5 -0.2) (size 0.38 1.72) (layers "F.Cu" "F.Mask")
      (net 86 "SGPIO1_DO") (pinfunction "B34") (pintype "passive"))
    (pad "B35" smd rect (at 5.6 -0.2) (size 0.38 1.72) (layers "F.Cu" "F.Mask")
      (net 277 "SGPIO1_CLK") (pinfunction "B35") (pintype "passive"))
    (pad "B36" smd rect (at 6.2 -0.2) (size 0.38 1.72) (layers "F.Cu" "F.Mask")
      (net 87 "SGPIO1_DI") (pinfunction "B36") (pintype "passive"))
    (pad "B37" smd rect (at 6.8 -0.2) (size 0.38 1.72) (layers "F.Cu" "F.Mask")
      (net 88 "SGPIO1_LD") (pinfunction "B37") (pintype "passive"))
    (pad "B38" smd rect (at 7.4 0) (size 0.38 2.12) (layers "F.Cu" "F.Mask")
      (net 1 "GND") (pinfunction "B38") (pintype "passive"))
    (pad "B39" smd rect (at 8 -0.2) (size 0.38 1.72) (layers "F.Cu" "F.Mask")
      (net 89 "SGPIO_RESET_N") (pinfunction "B39") (pintype "passive"))
    (pad "B40" smd rect (at 8.6 -0.2) (size 0.38 1.72) (layers "F.Cu" "F.Mask")
      (net 90 "SGPIO_INTR_N") (pinfunction "B40") (pintype "passive"))
    (pad "B41" smd rect (at 9.2 -0.2) (size 0.38 1.72) (layers "F.Cu" "F.Mask")
      (net 414 "3V0_BAT") (pinfunction "B41") (pintype "passive"))
    (pad "B42" smd rect (at 9.8 -0.2) (size 0.38 1.72) (layers "F.Cu" "F.Mask")
      (net 91 "QSPI0_CS1_N") (pinfunction "B42") (pintype "passive"))
    (pad "B43" smd rect (at 14.715 -0.2) (size 0.38 1.72) (layers "F.Cu" "F.Mask")
      (net 92 "QSPI1_CLK") (pinfunction "B43") (pintype "passive"))
    (pad "B44" smd rect (at 15.3 -0.2) (size 0.38 1.72) (layers "F.Cu" "F.Mask")
      (net 93 "QSPI1_CS0_N") (pinfunction "B44") (pintype "passive"))
    (pad "B45" smd rect (at 15.9 -0.2) (size 0.38 1.72) (layers "F.Cu" "F.Mask")
      (net 94 "QSPI1_D0") (pinfunction "B45") (pintype "passive"))
    (pad "B46" smd rect (at 16.5 -0.2) (size 0.38 1.72) (layers "F.Cu" "F.Mask")
      (net 95 "QSPI1_D1") (pinfunction "B46") (pintype "passive"))
    (pad "B47" smd rect (at 17.1 -0.2) (size 0.38 1.72) (layers "F.Cu" "F.Mask")
      (net 96 "QSPI1_D2") (pinfunction "B47") (pintype "passive"))
  )
)
